# BASEBOARD_FAB2 (Tioga Pass) — schematic netlist excerpt (pin names and nets, part order shuffled) for the footprints in the layout excerpt that follows; sources: Cadence DE-HDL packaged netlist, KiCad conversion of Wiwynn_Tioga_Pass_MB.brd

CT34  CAP  1000PF 50V 10% X7R  pkg 0402LF  page 204 : A = A_TSENSE_PVCCIN_CPU0 ; B = GND
R3T1  RES  33.2 1% CHIP  pkg 0402  page 153 : A = SPI_BIOS_SOCKET_IO3 ; B = PU_BIOS_SPI_HOLD1_N
C7P3  CAP  47UF 4V 20% X6S  pkg 0805  page 76 : A = PVCCIO_CPU1 ; B = GND

(kicad_pcb
	(version 20260206)
	(generator "pcbnew")
	(generator_version "10.0")
	(general
		(thickness 1.6)
		(legacy_teardrops no)
	)
	(paper "A4")
	(title_block
		(title "Wiwynn_Tioga_Pass_MB.brd")
		(comment 1 "Tioga Pass / footprints 3168-3170 of 4770")
	)
	(layers
		(0 "F.Cu" signal "TOP")
		(4 "In1.Cu" signal "L2GND")
		(6 "In2.Cu" signal "L3")
		(8 "In3.Cu" signal "L4GND")
		(10 "In4.Cu" signal "L5")
		(12 "In5.Cu" signal "L6GND")
		(14 "In6.Cu" signal "L7VCC")
		(16 "In7.Cu" signal "L8VCC")
		(18 "In8.Cu" signal "L9GND")
		(20 "In9.Cu" signal "L10")
		(22 "In10.Cu" signal "L11GND")
		(24 "In11.Cu" signal "L12")
		(26 "In12.Cu" signal "L13GND")
		(2 "B.Cu" signal "BOTTOM")
		(9 "F.Adhes" user "F.Adhesive")
		(11 "B.Adhes" user "B.Adhesive")
		(13 "F.Paste" user "Package Geometry/Pastemask Top")
		(15 "B.Paste" user "Package Geometry/Pastemask Bottom")
		(5 "F.SilkS" user "Ref Des/Silkscreen Top")
		(7 "B.SilkS" user "Ref Des/Silkscreen Bottom")
		(1 "F.Mask" user "Board Geometry/Soldermask Top")
		(3 "B.Mask" user "Board Geometry/Soldermask Bottom")
		(17 "Dwgs.User" user "User.Drawings")
		(19 "Cmts.User" user "User.Comments")
		(21 "Eco1.User" user "User.Eco1")
		(23 "Eco2.User" user "User.Eco2")
		(25 "Edge.Cuts" user "Board Geometry/Outline")
		(27 "Margin" user)
		(31 "F.CrtYd" user "Package Geometry/Place Bound Top")
		(29 "B.CrtYd" user "Package Geometry/Place Bound Bottom")
		(35 "F.Fab" user "Ref Des/Assembly Top")
		(33 "B.Fab" user "Ref Des/Assembly Bottom")
	)
	(footprint ""
		(layer "B.Cu")
		(at 115.734592 -80.096614 180)
		(property "Reference" "C7P3"
			(at 0 0 0)
			(layer "B.SilkS")
			(hide yes)
			(effects
				(font
					(size 1.27 1.27)
				)
				(justify mirror)
			)
		)
		(property "Value" ""
			(at 0 0 0)
			(layer "B.Fab")
			(effects
				(font
					(size 1.27 1.27)
				)
				(justify mirror)
			)
		)
		(duplicate_pad_numbers_are_jumpers no)
		(fp_poly
			(pts
				(xy 0.7239 -0.2159) (xy -0.7239 -0.2159) (xy -0.7239 1.9939) (xy 0.7239 1.9939)
			)
			(stroke
				(width 0)
				(type default)
			)
			(fill no)
			(layer "B.CrtYd")
		)
		(fp_line
			(start 0.7239 1.9939)
			(end -0.7239 1.9939)
			(stroke
				(width 0.1)
				(type default)
			)
			(layer "B.Fab")
		)
		(fp_line
			(start 0.7239 -0.2159)
			(end 0.7239 1.9939)
			(stroke
				(width 0.1)
				(type default)
			)
			(layer "B.Fab")
		)
		(fp_line
			(start -0.7239 1.9939)
			(end -0.7239 -0.2159)
			(stroke
				(width 0.1)
				(type default)
			)
			(layer "B.Fab")
		)
		(fp_line
			(start -0.7239 -0.2159)
			(end 0.7239 -0.2159)
			(stroke
				(width 0.1)
				(type default)
			)
			(layer "B.Fab")
		)
		(pad "1" smd rect
			(at 0 0)
			(size 1.27 1.016)
			(layers "B.Cu" "B.Mask" "B.Paste")
			(net "PVCCIO_CPU1")
		)
		(pad "2" smd rect
			(at 0 1.778)
			(size 1.27 1.016)
			(layers "B.Cu" "B.Mask" "B.Paste")
			(net "GND")
		)
		(zone
			(layer "B.Cu")
			(hatch none 0.5)
			(connect_pads
				(clearance 0)
			)
			(min_thickness 0.25)
			(keepout
				(tracks not_allowed)
				(vias allowed)
				(pads allowed)
				(copperpour not_allowed)
				(footprints allowed)
			)
			(placement
				(enabled no)
				(sheetname "")
			)
			(fill
				(thermal_gap 0.5)
				(thermal_bridge_width 0.5)
				(island_removal_mode 0)
			)
			(polygon
				(pts
					(xy 115.099592 -80.604614) (xy 116.369592 -80.604614) (xy 116.369592 -81.366614) (xy 115.099592 -81.366614)
				)
			)
		)
	)
	(footprint ""
		(layer "B.Cu")
		(at 195.3006 -88.4428 90)
		(property "Reference" "CT34"
			(at 0.8382 -0.84963 90)
			(unlocked yes)
			(layer "B.SilkS")
			(effects
				(font
					(size 0.7874 0.5842)
					(thickness 0.1524)
				)
				(justify left mirror)
			)
		)
		(property "Value" ""
			(at 0 0 90)
			(layer "B.Fab")
			(effects
				(font
					(size 1.27 1.27)
				)
				(justify mirror)
			)
		)
		(duplicate_pad_numbers_are_jumpers no)
		(fp_poly
			(pts
				(xy -0.3048 -0.1016) (xy -0.3048 0.9906) (xy 0.3048 0.9906) (xy 0.3048 -0.1016)
			)
			(stroke
				(width 0)
				(type default)
			)
			(fill no)
			(layer "B.CrtYd")
		)
		(fp_line
			(start 0.3048 -0.1016)
			(end 0.3048 0.9906)
			(stroke
				(width 0.1)
				(type default)
			)
			(layer "B.Fab")
		)
		(fp_line
			(start -0.3048 -0.1016)
			(end 0.3048 -0.1016)
			(stroke
				(width 0.1)
				(type default)
			)
			(layer "B.Fab")
		)
		(fp_line
			(start 0.3048 0.9906)
			(end -0.3048 0.9906)
			(stroke
				(width 0.1)
				(type default)
			)
			(layer "B.Fab")
		)
		(fp_line
			(start -0.3048 0.9906)
			(end -0.3048 -0.1016)
			(stroke
				(width 0.1)
				(type default)
			)
			(layer "B.Fab")
		)
		(pad "1" smd rect
			(at 0 0 270)
			(size 0.508 0.508)
			(layers "B.Cu" "B.Mask" "B.Paste")
			(net "A_TSENSE_PVCCIN_CPU0")
		)
		(pad "2" smd rect
			(at 0 0.889 270)
			(size 0.508 0.508)
			(layers "B.Cu" "B.Mask" "B.Paste")
			(net "GND")
		)
		(zone
			(layer "B.Cu")
			(hatch none 0.5)
			(connect_pads
				(clearance 0)
			)
			(min_thickness 0.25)
			(keepout
				(tracks allowed)
				(vias not_allowed)
				(pads allowed)
				(copperpour not_allowed)
				(footprints allowed)
			)
			(placement
				(enabled no)
				(sheetname "")
			)
			(fill
				(thermal_gap 0.5)
				(thermal_bridge_width 0.5)
				(island_removal_mode 0)
			)
			(polygon
				(pts
					(xy 195.5546 -88.6968) (xy 195.5546 -88.1888) (xy 195.9356 -88.1888) (xy 195.9356 -88.6968)
				)
			)
		)
		(zone
			(layer "B.Cu")
			(hatch none 0.5)
			(connect_pads
				(clearance 0)
			)
			(min_thickness 0.25)
			(keepout
				(tracks not_allowed)
				(vias allowed)
				(pads allowed)
				(copperpour not_allowed)
				(footprints allowed)
			)
			(placement
				(enabled no)
				(sheetname "")
			)
			(fill
				(thermal_gap 0.5)
				(thermal_bridge_width 0.5)
				(island_removal_mode 0)
			)
			(polygon
				(pts
					(xy 195.9356 -88.6968) (xy 195.9356 -88.1888) (xy 195.5546 -88.1888) (xy 195.5546 -88.6968)
				)
			)
		)
	)
	(footprint ""
		(layer "B.Cu")
		(at 399.923 -57.658)
		(property "Reference" "R3T1"
			(at 0 0 0)
			(layer "B.SilkS")
			(hide yes)
			(effects
				(font
					(size 1.27 1.27)
				)
				(justify mirror)
			)
		)
		(property "Value" ""
			(at 0 0 0)
			(layer "B.Fab")
			(effects
				(font
					(size 1.27 1.27)
				)
				(justify mirror)
			)
		)
		(duplicate_pad_numbers_are_jumpers no)
		(fp_poly
			(pts
				(xy 0.2794 -0.1016) (xy -0.2794 -0.1016) (xy -0.2794 0.9906) (xy 0.2794 0.9906)
			)
			(stroke
				(width 0)
				(type default)
			)
			(fill no)
			(layer "B.CrtYd")
		)
		(fp_line
			(start -0.2794 -0.1016)
			(end 0.2794 -0.1016)
			(stroke
				(width 0.1)
				(type default)
			)
			(layer "B.Fab")
		)
		(fp_line
			(start -0.2794 0.9906)
			(end -0.2794 -0.1016)
			(stroke
				(width 0.1)
				(type default)
			)
			(layer "B.Fab")
		)
		(fp_line
			(start 0.2794 -0.1016)
			(end 0.2794 0.9906)
			(stroke
				(width 0.1)
				(type default)
			)
			(layer "B.Fab")
		)
		(fp_line
			(start 0.2794 0.9906)
			(end -0.2794 0.9906)
			(stroke
				(width 0.1)
				(type default)
			)
			(layer "B.Fab")
		)
		(pad "1" smd rect
			(at 0 0 180)
			(size 0.508 0.508)
			(layers "B.Cu" "B.Mask" "B.Paste")
			(net "SPI_BIOS_SOCKET_IO3")
		)
		(pad "2" smd rect
			(at 0 0.889 180)
			(size 0.508 0.508)
			(layers "B.Cu" "B.Mask" "B.Paste")
			(net "PU_BIOS_SPI_HOLD1_N")
		)
		(zone
			(layer "B.Cu")
			(hatch none 0.5)
			(connect_pads
				(clearance 0)
			)
			(min_thickness 0.25)
			(keepout
				(tracks allowed)
				(vias not_allowed)
				(pads allowed)
				(copperpour not_allowed)
				(footprints allowed)
			)
			(placement
				(enabled no)
				(sheetname "")
			)
			(fill
				(thermal_gap 0.5)
				(thermal_bridge_width 0.5)
				(island_removal_mode 0)
			)
			(polygon
				(pts
					(xy 400.177 -57.404) (xy 399.669 -57.404) (xy 399.669 -57.023) (xy 400.177 -57.023)
				)
			)
		)
		(zone
			(layer "B.Cu")
			(hatch none 0.5)
			(connect_pads
				(clearance 0)
			)
			(min_thickness 0.25)
			(keepout
				(tracks not_allowed)
				(vias allowed)
				(pads allowed)
				(copperpour not_allowed)
				(footprints allowed)
			)
			(placement
				(enabled no)
				(sheetname "")
			)
			(fill
				(thermal_gap 0.5)
				(thermal_bridge_width 0.5)
				(island_removal_mode 0)
			)
			(polygon
				(pts
					(xy 400.177 -57.023) (xy 399.669 -57.023) (xy 399.669 -57.404) (xy 400.177 -57.404)
				)
			)
		)
	)
)
